FILE_TYPE = CONNECTIVITY;
{Allegro Design Entry HDL 16.6-p007 (v16-6-112F) 10/10/2012}
"PAGE_NUMBER" = 138;
0"NC";
1"P3V3_STBY\g";
2"P3V3_STBY\g";
3"P3V3_STBY\g";
4"P3V3_STBY\g";
5"P3V3_STBY\g";
6"P3V3_STBY\g";
7"P3V3_STBY\g";
8"P3V3_STBY\g";
9"P3V3_STBY\g";
10"P3V3_STBY\g";
11"P3V3_STBY\g";
12"P3V3_STBY\g";
13"P3V3_STBY\g";
14"P3V3_STBY\g";
15"SMB_SMLINK0_STBY_LVC3_SDA";
16"SMB_SMLINK0_STBY_LVC3_SCL";
17"SMB_HOST_STBY_LVC3_SDA_R1";
18"SMB_HOST_STBY_LVC3_SCL_R1";
19"SMB_HOST_STBY_LVC3_SDA";
20"SMB_VR_STBY_LVC3_SCL_R1";
21"SMB_VR_STBY_LVC3_SDA_R1";
22"SMB_VR_STBY_LVC3_SCL";
23"SMB_VR_STBY_LVC3_SDA";
24"SMB_SLOTX24_PCH_STBY_LVC3_SDA";
25"SMB_SLOTX24_PCH_STBY_LVC3_SCL";
26"SMB_HOST_STBY_LVC3_SDA_R5";
27"SMB_HOST_STBY_LVC3_SCL_R5";
28"SMB_OCP_FRU_STBY_LVC3_SCL";
29"SMB_OCP_FRU_STBY_LVC3_SDA";
30"SMB_LAN_STBY_LVC3_SDA";
31"SMB_LAN_STBY_LVC3_SCL";
32"SMB_BMC_PMBUS_STBY_LVC3_SCL";
33"SMB_HOST_STBY_LVC3_SCL";
34"SMB_LAN_STBY_LVC3_SDA_R1";
35"SMB_LAN_STBY_LVC3_SCL_R2";
36"SMB_LAN_STBY_LVC3_SDA_R2";
37"SMB_LAN_STBY_LVC3_SCL_R1";
38"SMB_SMLINK0_STBY_LVC3_SCL_R1";
39"SMB_SMLINK0_STBY_LVC3_SDA_R1";
40"SMB_BMC_PMBUS_STBY_LVC3_SDA";
41"SMB_HOST_STBY_LVC3_SDA";
42"SMB_HOST_STBY_LVC3_SCL";
%"P3V3_STBY"
"1","(500,4725)","0","mstr_symbols","I138";
;
VOLTAGE"3.3V"
SIZE"1B"
CDS_LIB"mstr_symbols"
BODY_TYPE"PLUMBING"
HDL_POWER"P3V3_STBY";
"G\NAC"1;
%"P3V3_STBY"
"1","(850,4675)","0","mstr_symbols","I139";
;
VOLTAGE"3.3V"
CDS_LIB"mstr_symbols"
SIZE"1B"
BODY_TYPE"PLUMBING"
HDL_POWER"P3V3_STBY";
"G\NAC"2;
%"P3V3_STBY"
"1","(500,2825)","0","mstr_symbols","I140";
;
SIZE"1B"
CDS_LIB"mstr_symbols"
VOLTAGE"3.3V"
BODY_TYPE"PLUMBING"
HDL_POWER"P3V3_STBY";
"G\NAC"3;
%"P3V3_STBY"
"1","(875,2775)","0","mstr_symbols","I141";
;
CDS_LIB"mstr_symbols"
SIZE"1B"
VOLTAGE"3.3V"
BODY_TYPE"PLUMBING"
HDL_POWER"P3V3_STBY";
"G\NAC"4;
%"P3V3_STBY"
"1","(-3175,5200)","0","mstr_symbols","I144";
;
VOLTAGE"3.3V"
CDS_LIB"mstr_symbols"
SIZE"1B"
BODY_TYPE"PLUMBING"
HDL_POWER"P3V3_STBY";
"G\NAC"5;
%"P3V3_STBY"
"1","(-2775,5150)","0","mstr_symbols","I145";
;
VOLTAGE"3.3V"
SIZE"1B"
CDS_LIB"mstr_symbols"
BODY_TYPE"PLUMBING"
HDL_POWER"P3V3_STBY";
"G\NAC"6;
%"P3V3_STBY"
"1","(-3150,2300)","0","mstr_symbols","I150";
;
SIZE"1B"
CDS_LIB"mstr_symbols"
VOLTAGE"3.3V"
BODY_TYPE"PLUMBING"
HDL_POWER"P3V3_STBY";
"G\NAC"7;
%"P3V3_STBY"
"1","(-2750,2250)","0","mstr_symbols","I151";
;
VOLTAGE"3.3V"
SIZE"1B"
CDS_LIB"mstr_symbols"
BODY_TYPE"PLUMBING"
HDL_POWER"P3V3_STBY";
"G\NAC"8;
%"RES"
"1","(-3100,1325)","0","mstr_discrete","I158";
;
PART_NUMBER"G21796-173"
LOCATION"R2U8"
PACK_TYPE"0402"
MATERIAL"EMPTY"
TOLERANCE"1%"
VALUE"20.0"
WATTAGE"1/16W"
CDS_LOCATION"R2U8"
CDS_LIB"mstr_discrete"
CDS_SEC"1"
$SEC"1"
ROOM"SMBUS"
SKU"A"
BOM_COST"SM_CONTROLLER";
"B"
$PN"2"28;
"A"
$PN"1"31;
%"RES"
"1","(-3100,1425)","0","mstr_discrete","I159";
;
TOLERANCE"1%"
LOCATION"R2U12"
PACK_TYPE"0402"
VALUE"20.0"
WATTAGE"1/16W"
PART_NUMBER"G21796-173"
MATERIAL"EMPTY"
CDS_LOCATION"R2U12"
CDS_LIB"mstr_discrete"
$SEC"1"
CDS_SEC"1"
ROOM"SMBUS"
SKU"A"
BOM_COST"SM_CONTROLLER";
"B"
$PN"2"29;
"A"
$PN"1"30;
%"RES"
"1","(100,2275)","0","mstr_discrete","I163";
;
CDS_SEC"1"
PACK_TYPE"0402"
WATTAGE"1/16W"
TOLERANCE"1%"
MATERIAL"CHIP"
PART_NUMBER"G21796-173"
VALUE"20.0"
LOCATION"R8D7"
BOM_COST"SM_CONTROLLER"
CDS_LOCATION"R8D7"
SEC"1"
SEC_TYPE"0402"
ROOM"SMBUS"
CDS_LIB"mstr_discrete";
"B"
$PN"2"23;
"A"
$PN"1"21;
%"RES"
"1","(100,2125)","0","mstr_discrete","I164";
;
CDS_SEC"1"
MATERIAL"CHIP"
WATTAGE"1/16W"
PACK_TYPE"0402"
TOLERANCE"1%"
LOCATION"R8D4"
PART_NUMBER"G21796-173"
VALUE"20.0"
SEC"1"
BOM_COST"SM_CONTROLLER"
SEC_TYPE"0402"
ROOM"SMBUS"
CDS_LOCATION"R8D4"
CDS_LIB"mstr_discrete";
"B"
$PN"2"22;
"A"
$PN"1"20;
%"RES"
"1","(-3950,1775)","0","mstr_discrete","I165";
;
CDS_SEC"1"
MATERIAL"CHIP"
TOLERANCE"1%"
LOCATION"R2U9"
WATTAGE"1/16W"
VALUE"20.0"
PART_NUMBER"G21796-173"
PACK_TYPE"0402"
CDS_LIB"mstr_discrete"
CDS_LOCATION"R2U9"
ROOM"SMBUS"
SEC"1"
SEC_TYPE"0402"
BOM_COST"SM_CONTROLLER";
"B"
$PN"2"30;
"A"
$PN"1"34;
%"RES"
"1","(-3950,1625)","0","mstr_discrete","I166";
;
CDS_SEC"1"
PACK_TYPE"0402"
VALUE"20.0"
TOLERANCE"1%"
LOCATION"R2U6"
MATERIAL"CHIP"
WATTAGE"1/16W"
PART_NUMBER"G21796-173"
CDS_LOCATION"R2U6"
CDS_LIB"mstr_discrete"
ROOM"SMBUS"
SEC_TYPE"0402"
BOM_COST"SM_CONTROLLER"
SEC"1";
"B"
$PN"2"31;
"A"
$PN"1"37;
%"RES"
"1","(-3775,3700)","0","mstr_discrete","I167";
;
CDS_SEC"1"
LOCATION"R8C20"
VALUE"20.0"
MATERIAL"CHIP"
WATTAGE"1/16W"
PACK_TYPE"0402"
TOLERANCE"1%"
PART_NUMBER"G21796-173"
SEC"1"
SEC_TYPE"0402"
BOM_COST"SM_CONTROLLER"
ROOM"SMBUS"
CDS_LOCATION"R8C20"
CDS_LIB"mstr_discrete";
"B"
$PN"2"41;
"A"
$PN"1"17;
%"RES"
"1","(-3775,3550)","0","mstr_discrete","I168";
;
CDS_SEC"1"
WATTAGE"1/16W"
VALUE"20.0"
PART_NUMBER"G21796-173"
MATERIAL"CHIP"
PACK_TYPE"0402"
TOLERANCE"1%"
LOCATION"R8C14"
BOM_COST"SM_CONTROLLER"
ROOM"SMBUS"
SEC_TYPE"0402"
SEC"1"
CDS_LOCATION"R8C14"
CDS_LIB"mstr_discrete";
"B"
$PN"2"42;
"A"
$PN"1"18;
%"RES"
"1","(-3975,4625)","0","mstr_discrete","I169";
;
CDS_SEC"1"
MATERIAL"CHIP"
VALUE"20.0"
WATTAGE"1/16W"
LOCATION"R8C11"
TOLERANCE"1%"
PART_NUMBER"G21796-173"
PACK_TYPE"0402"
CDS_LOCATION"R8C11"
CDS_LIB"mstr_discrete"
ROOM"SMBUS"
SEC"1"
SEC_TYPE"0402"
BOM_COST"SM_CONTROLLER";
"B"
$PN"2"15;
"A"
$PN"1"39;
%"RES"
"1","(-3975,4475)","0","mstr_discrete","I170";
;
CDS_SEC"1"
VALUE"20.0"
TOLERANCE"1%"
MATERIAL"CHIP"
PACK_TYPE"0402"
PART_NUMBER"G21796-173"
WATTAGE"1/16W"
LOCATION"R8C12"
CDS_LOCATION"R8C12"
CDS_LIB"mstr_discrete"
ROOM"SMBUS"
SEC_TYPE"0402"
SEC"1"
BOM_COST"SM_CONTROLLER";
"B"
$PN"2"16;
"A"
$PN"1"38;
%"RES"
"1","(-3975,2150)","0","mstr_discrete","I171";
;
CDS_SEC"1"
VALUE"0.0"
TOLERANCE"5%"
MATERIAL"CHIP"
PACK_TYPE"0402"
LOCATION"R2N20"
WATTAGE"1/16W"
PART_NUMBER"G21497-005"
CDS_LIB"mstr_discrete"
CDS_LOCATION"R2N20"
ROOM"SMBUS"
SEC_TYPE"0402"
BOM_COST"SM_CONTROLLER"
SEC"1";
"B"
$PN"2"30;
"A"
$PN"1"36;
%"RES"
"1","(-3975,2000)","0","mstr_discrete","I175";
;
CDS_SEC"1"
PART_NUMBER"G21497-005"
VALUE"0.0"
MATERIAL"CHIP"
TOLERANCE"5%"
WATTAGE"1/16W"
PACK_TYPE"0402"
LOCATION"R2N21"
CDS_LIB"mstr_discrete"
CDS_LOCATION"R2N21"
ROOM"SMBUS"
SEC_TYPE"0402"
BOM_COST"SM_CONTROLLER"
SEC"1";
"B"
$PN"2"31;
"A"
$PN"1"35;
%"P3V3_STBY"
"1","(-2775,3150)","0","mstr_symbols","I179";
;
SIZE"1B"
CDS_LIB"mstr_symbols"
VOLTAGE"3.3V"
BODY_TYPE"PLUMBING"
HDL_POWER"P3V3_STBY";
"G\NAC"9;
%"P3V3_STBY"
"1","(-3175,3200)","0","mstr_symbols","I180";
;
VOLTAGE"3.3V"
CDS_LIB"mstr_symbols"
SIZE"1B"
BODY_TYPE"PLUMBING"
HDL_POWER"P3V3_STBY";
"G\NAC"10;
%"RES"
"1","(-3175,2975)","5","mstr_discrete","I186";
;
CDS_SEC"1"
CDS_LOCATION"R8B24"
TOLERANCE"5%"
PART_NUMBER"G21497-013"
MATERIAL"CHIP"
PACK_TYPE"0402"
VALUE"3.3K"
WATTAGE"1/16W"
LOCATION"R8B24"
SEC"1"
SEC_TYPE"0402"
CDS_LIB"mstr_discrete";
"B"
$PN"2"26;
"A"
$PN"1"10;
%"RES"
"1","(-2775,2925)","5","mstr_discrete","I187";
;
CDS_SEC"1"
CDS_LOCATION"R8B26"
PACK_TYPE"0402"
PART_NUMBER"G21497-013"
MATERIAL"CHIP"
WATTAGE"1/16W"
TOLERANCE"5%"
LOCATION"R8B26"
VALUE"3.3K"
SEC"1"
SEC_TYPE"0402"
CDS_LIB"mstr_discrete";
"B"
$PN"2"27;
"A"
$PN"1"9;
%"RES"
"1","(-4000,2800)","0","mstr_discrete","I194";
;
CDS_SEC"1"
PACK_TYPE"0402"
MATERIAL"CHIP"
PART_NUMBER"G21796-173"
WATTAGE"1/16W"
TOLERANCE"1%"
LOCATION"R8W5"
VALUE"20.0"
BOM_COST"SM_CONTROLLER"
ROOM"SMBUS"
SEC_TYPE"0402"
SEC"1"
CDS_LIB"mstr_discrete"
CDS_LOCATION"R8W5";
"B"
$PN"2"27;
"A"
$PN"1"33;
%"RES"
"1","(-4000,2950)","0","mstr_discrete","I195";
;
CDS_SEC"1"
VALUE"20.0"
LOCATION"R8W4"
MATERIAL"CHIP"
PACK_TYPE"0402"
TOLERANCE"1%"
WATTAGE"1/16W"
PART_NUMBER"G21796-173"
SEC"1"
SEC_TYPE"0402"
BOM_COST"SM_CONTROLLER"
ROOM"SMBUS"
CDS_LIB"mstr_discrete"
CDS_LOCATION"R8W4";
"B"
$PN"2"26;
"A"
$PN"1"19;
%"RES"
"1","(-600,1650)","5","mstr_discrete","I198";
;
CDS_SEC"1"
CDS_LOCATION"R24W1"
VALUE"3.3K"
PACK_TYPE"0402"
LOCATION"R24W1"
TOLERANCE"5%"
PART_NUMBER"G21497-013"
MATERIAL"CHIP"
WATTAGE"1/16W"
CDS_LIB"mstr_discrete"
SEC_TYPE"0402"
SEC"1";
"B"
$PN"2"24;
"A"
$PN"1"11;
%"RES"
"1","(-200,1650)","5","mstr_discrete","I199";
;
CDS_SEC"1"
CDS_LOCATION"R24W2"
LOCATION"R24W2"
TOLERANCE"5%"
WATTAGE"1/16W"
VALUE"3.3K"
MATERIAL"CHIP"
PACK_TYPE"0402"
PART_NUMBER"G21497-013"
SEC"1"
SEC_TYPE"0402"
CDS_LIB"mstr_discrete";
"B"
$PN"2"25;
"A"
$PN"1"12;
%"P3V3_STBY"
"1","(-600,1900)","0","mstr_symbols","I200";
;
VOLTAGE"3.3V"
CDS_LIB"mstr_symbols"
SIZE"1B"
BODY_TYPE"PLUMBING"
HDL_POWER"P3V3_STBY";
"G\NAC"11;
%"P3V3_STBY"
"1","(-200,1900)","0","mstr_symbols","I201";
;
VOLTAGE"3.3V"
CDS_LIB"mstr_symbols"
SIZE"1B"
BODY_TYPE"PLUMBING"
HDL_POWER"P3V3_STBY";
"G\NAC"12;
%"RES"
"2","(-200,2550)","0","mstr_discrete","I202";
;
CDS_SEC"1"
TOLERANCE"1%"
VALUE"1.37K"
LOCATION"R8W7"
MATERIAL"CHIP"
PACK_TYPE"0402"
WATTAGE"1/16W"
PART_NUMBER"G21796-095"
CDS_LOCATION"R8W7"
SEC"1"
SEC_TYPE"0402"
CDS_LIB"mstr_discrete"
ROOM"SMBUS"
BOM_COST"SM_CONTROLLER";
"A"
$PN"1"13;
"B"
$PN"2"20;
%"P3V3_STBY"
"1","(-200,2800)","0","mstr_symbols","I203";
;
VOLTAGE"3.3V"
SIZE"1B"
CDS_LIB"mstr_symbols"
BODY_TYPE"PLUMBING"
HDL_POWER"P3V3_STBY";
"G\NAC"13;
%"P3V3_STBY"
"1","(-575,2850)","0","mstr_symbols","I204";
;
VOLTAGE"3.3V"
CDS_LIB"mstr_symbols"
SIZE"1B"
BODY_TYPE"PLUMBING"
HDL_POWER"P3V3_STBY";
"G\NAC"14;
%"RES"
"2","(-575,2600)","0","mstr_discrete","I205";
;
CDS_SEC"1"
VALUE"1.37K"
TOLERANCE"1%"
LOCATION"R8W6"
PACK_TYPE"0402"
PART_NUMBER"G21796-095"
MATERIAL"CHIP"
WATTAGE"1/16W"
CDS_LOCATION"R8W6"
SEC"1"
SEC_TYPE"0402"
CDS_LIB"mstr_discrete"
BOM_COST"SM_CONTROLLER"
ROOM"SMBUS";
"A"
$PN"1"14;
"B"
$PN"2"21;
%"RES"
"2","(500,4450)","0","mstr_discrete","I83";
;
CDS_SEC"1"
LOCATION"R2T53"
PART_NUMBER"G21796-235"
PACK_TYPE"0402"
WATTAGE"1/16W"
VALUE"665"
MATERIAL"CHIP"
TOLERANCE"1.0%"
CDS_LIB"mstr_discrete"
CDS_LOCATION"R2T53"
ROOM"SMBUS"
SEC"1"
SEC_TYPE"0402"
BOM_COST"SM_CONTROLLER";
"A"
$PN"1"1;
"B"
$PN"2"40;
%"RES"
"2","(850,4400)","0","mstr_discrete","I84";
;
CDS_SEC"1"
PACK_TYPE"0402"
MATERIAL"CHIP"
VALUE"665"
TOLERANCE"1.0%"
PART_NUMBER"G21796-235"
WATTAGE"1/16W"
LOCATION"R2T54"
CDS_LIB"mstr_discrete"
CDS_LOCATION"R2T54"
ROOM"SMBUS"
SEC"1"
SEC_TYPE"0402"
BOM_COST"SM_CONTROLLER";
"A"
$PN"1"2;
"B"
$PN"2"32;
%"RES"
"2","(500,2575)","0","mstr_discrete","I87";
;
CDS_SEC"1"
PART_NUMBER"G21796-095"
PACK_TYPE"0402"
MATERIAL"CHIP"
TOLERANCE"1%"
VALUE"1.37K"
LOCATION"R8D17"
WATTAGE"1/16W"
ROOM"SMBUS"
CDS_LOCATION"R8D17"
BOM_COST"SM_CONTROLLER"
CDS_LIB"mstr_discrete"
SEC_TYPE"0402"
SEC"1";
"A"
$PN"1"3;
"B"
$PN"2"23;
%"RES"
"2","(875,2525)","0","mstr_discrete","I88";
;
CDS_SEC"1"
PART_NUMBER"G21796-095"
MATERIAL"CHIP"
PACK_TYPE"0402"
WATTAGE"1/16W"
TOLERANCE"1%"
VALUE"1.37K"
LOCATION"R8D15"
BOM_COST"SM_CONTROLLER"
CDS_LOCATION"R8D15"
ROOM"SMBUS"
CDS_LIB"mstr_discrete"
SEC_TYPE"0402"
SEC"1";
"A"
$PN"1"4;
"B"
$PN"2"22;
%"RES"
"2","(-3175,4950)","0","mstr_discrete","I89";
;
CDS_SEC"1"
LOCATION"R2N8"
MATERIAL"CHIP"
WATTAGE"1/16W"
PACK_TYPE"0402"
PART_NUMBER"G21796-235"
VALUE"665"
TOLERANCE"1.0%"
CDS_LIB"mstr_discrete"
CDS_LOCATION"R2N8"
ROOM"SMBUS"
SEC"1"
SEC_TYPE"0402"
BOM_COST"SM_CONTROLLER";
"A"
$PN"1"5;
"B"
$PN"2"15;
%"RES"
"2","(-2775,4900)","0","mstr_discrete","I90";
;
CDS_SEC"1"
PACK_TYPE"0402"
MATERIAL"CHIP"
LOCATION"R2N5"
WATTAGE"1/16W"
TOLERANCE"1.0%"
VALUE"665"
PART_NUMBER"G21796-235"
CDS_LIB"mstr_discrete"
CDS_LOCATION"R2N5"
ROOM"SMBUS"
BOM_COST"SM_CONTROLLER"
SEC_TYPE"0402"
SEC"1";
"A"
$PN"1"6;
"B"
$PN"2"16;
%"RES"
"2","(-3150,2100)","0","mstr_discrete","I97";
;
CDS_SEC"1"
PACK_TYPE"0402"
MATERIAL"CHIP"
WATTAGE"1/16W"
TOLERANCE"1.0%"
PART_NUMBER"G21796-235"
LOCATION"R2U11"
VALUE"665"
CDS_LIB"mstr_discrete"
CDS_LOCATION"R2U11"
ROOM"SMBUS"
BOM_COST"SM_CONTROLLER"
SEC_TYPE"0402"
SEC"1";
"A"
$PN"1"7;
"B"
$PN"2"30;
%"RES"
"2","(-2750,2025)","0","mstr_discrete","I98";
;
CDS_SEC"1"
PACK_TYPE"0402"
PART_NUMBER"G21796-235"
MATERIAL"CHIP"
WATTAGE"1/16W"
TOLERANCE"1.0%"
VALUE"665"
LOCATION"R2U3"
CDS_LIB"mstr_discrete"
CDS_LOCATION"R2U3"
SEC"1"
ROOM"SMBUS"
SEC_TYPE"0402"
BOM_COST"SM_CONTROLLER";
"A"
$PN"1"8;
"B"
$PN"2"31;
END.
